(kicad_pcb
	(version 20260206)
	(generator "pcbnew")
	(generator_version "10.0")
	(general
		(thickness 1.6)
		(legacy_teardrops no)
	)
	(paper "A4")
	(title_block
		(title "baseboard — 13948-1b.1110WZS1818.brd")
		(comment 1 "Honey Badger (Wiwynn) / footprints 333-339 of 2523")
	)
	(layers
		(0 "F.Cu" signal "TOP")
		(4 "In1.Cu" signal "L2GND")
		(6 "In2.Cu" signal "L3")
		(8 "In3.Cu" signal "L4VCC")
		(10 "In4.Cu" signal "L5VCC")
		(12 "In5.Cu" signal "L6")
		(14 "In6.Cu" signal "L7GND")
		(2 "B.Cu" signal "BOTTOM")
		(9 "F.Adhes" user "F.Adhesive")
		(11 "B.Adhes" user "B.Adhesive")
		(13 "F.Paste" user "Package Geometry/Pastemask Top")
		(15 "B.Paste" user "Package Geometry/Pastemask Bottom")
		(5 "F.SilkS" user "Ref Des/Silkscreen Top")
		(7 "B.SilkS" user "Ref Des/Silkscreen Bottom")
		(1 "F.Mask" user "Board Geometry/Soldermask Top")
		(3 "B.Mask" user "Board Geometry/Soldermask Bottom")
		(17 "Dwgs.User" user "User.Drawings")
		(19 "Cmts.User" user "User.Comments")
		(21 "Eco1.User" user "User.Eco1")
		(23 "Eco2.User" user "User.Eco2")
		(25 "Edge.Cuts" user "Board Geometry/Outline")
		(27 "Margin" user)
		(31 "F.CrtYd" user "Package Geometry/Place Bound Top")
		(29 "B.CrtYd" user "Package Geometry/Place Bound Bottom")
		(35 "F.Fab" user "Ref Des/Assembly Top")
		(33 "B.Fab" user "Ref Des/Assembly Bottom")
	)
	(footprint ""
		(layer "F.Cu")
		(at 17.385538 -172.926756)
		(property "Reference" "SU70"
			(at 0 0 0)
			(layer "F.SilkS")
			(hide yes)
			(effects
				(font
					(size 1.27 1.27)
				)
			)
		)
		(property "Value" "SNLVC8T245DGVR-GP"
			(at 0 -11.1252 0)
			(unlocked yes)
			(layer "F.Fab")
			(hide yes)
			(effects
				(font
					(size 1.016 1.016)
					(thickness 0.1524)
				)
			)
		)
		(property "Device Type" "TVSOP24H48"
			(at 0 -12.6492 0)
			(unlocked yes)
			(layer "F.Fab")
			(hide yes)
			(effects
				(font
					(size 1.016 1.016)
					(thickness 0.1524)
				)
			)
		)
		(duplicate_pad_numbers_are_jumpers no)
		(fp_line
			(start -2.9337 -1.397)
			(end -2.9337 1.397)
			(stroke
				(width 0.1524)
				(type default)
			)
			(layer "F.SilkS")
		)
		(fp_line
			(start -2.9337 -0.3683)
			(end -2.5654 0)
			(stroke
				(width 0.1524)
				(type default)
			)
			(layer "F.SilkS")
		)
		(fp_line
			(start -2.9337 1.397)
			(end 2.2987 1.397)
			(stroke
				(width 0.1524)
				(type default)
			)
			(layer "F.SilkS")
		)
		(fp_line
			(start -2.7559 1.397)
			(end -2.7559 3.8354)
			(stroke
				(width 0.508)
				(type default)
			)
			(layer "F.SilkS")
		)
		(fp_line
			(start -2.5654 0)
			(end -2.9337 0.3683)
			(stroke
				(width 0.1524)
				(type default)
			)
			(layer "F.SilkS")
		)
		(fp_line
			(start 2.2987 -1.397)
			(end -2.9337 -1.397)
			(stroke
				(width 0.1524)
				(type default)
			)
			(layer "F.SilkS")
		)
		(fp_line
			(start 2.2987 1.397)
			(end 2.2987 -1.397)
			(stroke
				(width 0.1524)
				(type default)
			)
			(layer "F.SilkS")
		)
		(fp_rect
			(start -3.0099 4.0894)
			(end 3.0099 -4.0894)
			(stroke
				(width 0)
				(type default)
			)
			(fill no)
			(layer "F.CrtYd")
		)
		(fp_poly
			(pts
				(xy -3.0099 -4.0894) (xy 3.0099 -4.0894) (xy 3.0099 4.0894) (xy -3.0099 4.0894)
			)
			(stroke
				(width 0)
				(type default)
			)
			(fill no)
			(layer "F.Fab")
		)
		(pad "1" smd rect
			(at -2.19964 2.8194)
			(size 0.2032 1.524)
			(layers "F.Cu" "F.Mask" "F.Paste")
			(net "P1V8_E")
		)
		(pad "2" smd rect
			(at -1.79959 2.8194)
			(size 0.2032 1.524)
			(layers "F.Cu" "F.Mask" "F.Paste")
			(net "GND")
		)
		(pad "3" smd rect
			(at -1.39954 2.8194)
			(size 0.2032 1.524)
			(layers "F.Cu" "F.Mask" "F.Paste")
			(net "SAS_HDD_LED4")
		)
		(pad "4" smd rect
			(at -0.99949 2.8194)
			(size 0.2032 1.524)
			(layers "F.Cu" "F.Mask" "F.Paste")
			(net "SAS_HDD_LED5")
		)
		(pad "5" smd rect
			(at -0.59944 2.8194)
			(size 0.2032 1.524)
			(layers "F.Cu" "F.Mask" "F.Paste")
			(net "SAS_HDD_LED6")
		)
		(pad "6" smd rect
			(at -0.19939 2.8194)
			(size 0.2032 1.524)
			(layers "F.Cu" "F.Mask" "F.Paste")
			(net "SAS_HDD_LED7")
		)
		(pad "7" smd rect
			(at 0.19939 2.8194)
			(size 0.2032 1.524)
			(layers "F.Cu" "F.Mask" "F.Paste")
			(net "SAS_HDD_LED8")
		)
		(pad "8" smd rect
			(at 0.59944 2.8194)
			(size 0.2032 1.524)
			(layers "F.Cu" "F.Mask" "F.Paste")
			(net "SAS_HDD_LED9")
		)
		(pad "9" smd rect
			(at 0.99949 2.8194)
			(size 0.2032 1.524)
			(layers "F.Cu" "F.Mask" "F.Paste")
			(net "SAS_HDD_LED10")
		)
		(pad "10" smd rect
			(at 1.39954 2.8194)
			(size 0.2032 1.524)
			(layers "F.Cu" "F.Mask" "F.Paste")
			(net "SAS_HDD_LED11")
		)
		(pad "11" smd rect
			(at 1.79959 2.8194)
			(size 0.2032 1.524)
			(layers "F.Cu" "F.Mask" "F.Paste")
			(net "GND")
		)
		(pad "12" smd rect
			(at 2.19964 2.8194)
			(size 0.2032 1.524)
			(layers "F.Cu" "F.Mask" "F.Paste")
			(net "GND")
		)
		(pad "13" smd rect
			(at 2.19964 -2.8194)
			(size 0.2032 1.524)
			(layers "F.Cu" "F.Mask" "F.Paste")
			(net "GND")
		)
		(pad "14" smd rect
			(at 1.79959 -2.8194)
			(size 0.2032 1.524)
			(layers "F.Cu" "F.Mask" "F.Paste")
			(net "SAS_HDD_PRE15")
		)
		(pad "15" smd rect
			(at 1.39954 -2.8194)
			(size 0.2032 1.524)
			(layers "F.Cu" "F.Mask" "F.Paste")
			(net "SAS_HDD_PRE14")
		)
		(pad "16" smd rect
			(at 0.99949 -2.8194)
			(size 0.2032 1.524)
			(layers "F.Cu" "F.Mask" "F.Paste")
			(net "SAS_HDD_PRE13")
		)
		(pad "17" smd rect
			(at 0.59944 -2.8194)
			(size 0.2032 1.524)
			(layers "F.Cu" "F.Mask" "F.Paste")
			(net "SAS_HDD_PRE12")
		)
		(pad "18" smd rect
			(at 0.19939 -2.8194)
			(size 0.2032 1.524)
			(layers "F.Cu" "F.Mask" "F.Paste")
			(net "SAS_HDD_PRE11")
		)
		(pad "19" smd rect
			(at -0.19939 -2.8194)
			(size 0.2032 1.524)
			(layers "F.Cu" "F.Mask" "F.Paste")
			(net "SAS_HDD_PRE10")
		)
		(pad "20" smd rect
			(at -0.59944 -2.8194)
			(size 0.2032 1.524)
			(layers "F.Cu" "F.Mask" "F.Paste")
			(net "SAS_HDD_PRE9")
		)
		(pad "21" smd rect
			(at -0.99949 -2.8194)
			(size 0.2032 1.524)
			(layers "F.Cu" "F.Mask" "F.Paste")
			(net "SAS_HDD_PRE8")
		)
		(pad "22" smd rect
			(at -1.39954 -2.8194)
			(size 0.2032 1.524)
			(layers "F.Cu" "F.Mask" "F.Paste")
			(net "GND")
		)
		(pad "23" smd rect
			(at -1.79959 -2.8194)
			(size 0.2032 1.524)
			(layers "F.Cu" "F.Mask" "F.Paste")
			(net "P3V3_STBY")
		)
		(pad "24" smd rect
			(at -2.19964 -2.8194)
			(size 0.2032 1.524)
			(layers "F.Cu" "F.Mask" "F.Paste")
			(net "P3V3_STBY")
		)
	)
	(footprint ""
		(layer "F.Cu")
		(at 220.844872 -178.634136)
		(property "Reference" "R499"
			(at 0 0 0)
			(layer "F.SilkS")
			(hide yes)
			(effects
				(font
					(size 1.27 1.27)
				)
			)
		)
		(property "Value" "0R2J-2-GP"
			(at 0.064008 -3.993896 0)
			(unlocked yes)
			(layer "F.Fab")
			(hide yes)
			(effects
				(font
					(size 1.016 1.016)
					(thickness 0.1524)
				)
			)
		)
		(property "Device Type" "R402H16"
			(at 0.064008 -5.517896 0)
			(unlocked yes)
			(layer "F.Fab")
			(hide yes)
			(effects
				(font
					(size 1.016 1.016)
					(thickness 0.1524)
				)
			)
		)
		(duplicate_pad_numbers_are_jumpers no)
		(fp_line
			(start -0.508 -0.9398)
			(end -0.508 0.9398)
			(stroke
				(width 0.1524)
				(type default)
			)
			(layer "F.SilkS")
		)
		(fp_line
			(start 0.508 -0.9398)
			(end -0.508 -0.9398)
			(stroke
				(width 0.1524)
				(type default)
			)
			(layer "F.SilkS")
		)
		(fp_rect
			(start -0.508 0.9398)
			(end 0.508 -0.9398)
			(stroke
				(width 0)
				(type default)
			)
			(fill no)
			(layer "F.CrtYd")
		)
		(fp_rect
			(start -0.508 0.9398)
			(end 0.508 -0.9398)
			(stroke
				(width 0)
				(type default)
			)
			(fill no)
			(layer "F.Fab")
		)
		(pad "1" smd custom
			(at 0 -0.4445)
			(size 0.1397 0.1397)
			(layers "F.Cu" "F.Mask" "F.Paste")
			(net "HB_A_OUT_EXP")
			(options
				(clearance outline)
				(anchor circle)
			)
			(primitives
				(gr_poly
					(pts
						(arc
							(start -0.1778 -0.2794)
							(mid -0.249642 -0.249642)
							(end -0.2794 -0.1778)
						)
						(arc
							(start -0.2794 0.1778)
							(mid -0.249642 0.249642)
							(end -0.1778 0.2794)
						)
						(arc
							(start 0.1778 0.2794)
							(mid 0.249642 0.249642)
							(end 0.2794 0.1778)
						)
						(arc
							(start 0.2794 -0.1778)
							(mid 0.249642 -0.249642)
							(end 0.1778 -0.2794)
						)
					)
					(width 0)
					(fill yes)
				)
			)
		)
		(pad "2" smd custom
			(at 0 0.4445)
			(size 0.1397 0.1397)
			(layers "F.Cu" "F.Mask" "F.Paste")
			(net "HB_EXP_TO_BMC")
			(options
				(clearance outline)
				(anchor circle)
			)
			(primitives
				(gr_poly
					(pts
						(arc
							(start -0.1778 -0.2794)
							(mid -0.249642 -0.249642)
							(end -0.2794 -0.1778)
						)
						(arc
							(start -0.2794 0.1778)
							(mid -0.249642 0.249642)
							(end -0.1778 0.2794)
						)
						(arc
							(start 0.1778 0.2794)
							(mid 0.249642 0.249642)
							(end 0.2794 0.1778)
						)
						(arc
							(start 0.2794 -0.1778)
							(mid 0.249642 -0.249642)
							(end 0.1778 -0.2794)
						)
					)
					(width 0)
					(fill yes)
				)
			)
		)
	)
	(footprint ""
		(layer "F.Cu")
		(at 215.519 -184.531 -90)
		(property "Reference" "SC1309"
			(at 0 0 270)
			(layer "F.SilkS")
			(hide yes)
			(effects
				(font
					(size 1.27 1.27)
				)
			)
		)
		(property "Value" "SC10U6D3V5KX-4GP"
			(at -0.0762 -6.1214 270)
			(unlocked yes)
			(layer "F.Fab")
			(hide yes)
			(effects
				(font
					(size 1.016 1.016)
					(thickness 0.1524)
				)
			)
		)
		(property "Device Type" "C805H58"
			(at -0.0762 -8.1534 270)
			(unlocked yes)
			(layer "F.Fab")
			(hide yes)
			(effects
				(font
					(size 1.016 1.016)
					(thickness 0.1524)
				)
			)
		)
		(duplicate_pad_numbers_are_jumpers no)
		(fp_line
			(start 0.635 0)
			(end -0.635 0)
			(stroke
				(width 0.508)
				(type default)
			)
			(layer "F.SilkS")
		)
		(fp_rect
			(start -0.9652 1.778)
			(end 0.9652 -1.778)
			(stroke
				(width 0)
				(type default)
			)
			(fill no)
			(layer "F.CrtYd")
		)
		(fp_poly
			(pts
				(xy -0.9652 -1.778) (xy 0.9652 -1.778) (xy 0.9652 1.778) (xy -0.9652 1.778)
			)
			(stroke
				(width 0)
				(type default)
			)
			(fill no)
			(layer "F.Fab")
		)
		(pad "1" smd rect
			(at 0 -0.9652 270)
			(size 1.397 1.143)
			(layers "F.Cu" "F.Mask" "F.Paste")
			(net "HB_A_IN_EXP")
		)
		(pad "2" smd rect
			(at 0 0.9652 270)
			(size 1.397 1.143)
			(layers "F.Cu" "F.Mask" "F.Paste")
			(net "GND")
		)
	)
	(footprint ""
		(layer "F.Cu")
		(at 261.562596 -54.375812 -90)
		(property "Reference" "SR717"
			(at 0 0 270)
			(layer "F.SilkS")
			(hide yes)
			(effects
				(font
					(size 1.27 1.27)
				)
			)
		)
		(property "Value" "4K7R2F-GP"
			(at 0.064008 -3.993896 270)
			(unlocked yes)
			(layer "F.Fab")
			(hide yes)
			(effects
				(font
					(size 1.016 1.016)
					(thickness 0.1524)
				)
			)
		)
		(property "Device Type" "R402H16"
			(at 0.064008 -5.517896 270)
			(unlocked yes)
			(layer "F.Fab")
			(hide yes)
			(effects
				(font
					(size 1.016 1.016)
					(thickness 0.1524)
				)
			)
		)
		(duplicate_pad_numbers_are_jumpers no)
		(fp_line
			(start -0.508 -0.9398)
			(end -0.508 0.9398)
			(stroke
				(width 0.1524)
				(type default)
			)
			(layer "F.SilkS")
		)
		(fp_line
			(start 0.508 -0.9398)
			(end -0.508 -0.9398)
			(stroke
				(width 0.1524)
				(type default)
			)
			(layer "F.SilkS")
		)
		(fp_rect
			(start -0.508 0.9398)
			(end 0.508 -0.9398)
			(stroke
				(width 0)
				(type default)
			)
			(fill no)
			(layer "F.CrtYd")
		)
		(fp_rect
			(start -0.508 0.9398)
			(end 0.508 -0.9398)
			(stroke
				(width 0)
				(type default)
			)
			(fill no)
			(layer "F.Fab")
		)
		(pad "1" smd custom
			(at 0 -0.4445 270)
			(size 0.1397 0.1397)
			(layers "F.Cu" "F.Mask" "F.Paste")
			(net "P1V8_C")
			(options
				(clearance outline)
				(anchor circle)
			)
			(primitives
				(gr_poly
					(pts
						(arc
							(start -0.1778 -0.2794)
							(mid -0.249642 -0.249642)
							(end -0.2794 -0.1778)
						)
						(arc
							(start -0.2794 0.1778)
							(mid -0.249642 0.249642)
							(end -0.1778 0.2794)
						)
						(arc
							(start 0.1778 0.2794)
							(mid 0.249642 0.249642)
							(end 0.2794 0.1778)
						)
						(arc
							(start 0.2794 -0.1778)
							(mid 0.249642 -0.249642)
							(end 0.1778 -0.2794)
						)
					)
					(width 0)
					(fill yes)
				)
			)
		)
		(pad "2" smd custom
			(at 0 0.4445 270)
			(size 0.1397 0.1397)
			(layers "F.Cu" "F.Mask" "F.Paste")
			(net "IOC_EEPROM_A2")
			(options
				(clearance outline)
				(anchor circle)
			)
			(primitives
				(gr_poly
					(pts
						(arc
							(start -0.1778 -0.2794)
							(mid -0.249642 -0.249642)
							(end -0.2794 -0.1778)
						)
						(arc
							(start -0.2794 0.1778)
							(mid -0.249642 0.249642)
							(end -0.1778 0.2794)
						)
						(arc
							(start 0.1778 0.2794)
							(mid 0.249642 0.249642)
							(end 0.2794 0.1778)
						)
						(arc
							(start 0.2794 -0.1778)
							(mid 0.249642 -0.249642)
							(end 0.1778 -0.2794)
						)
					)
					(width 0)
					(fill yes)
				)
			)
		)
	)
	(footprint ""
		(layer "F.Cu")
		(at 174.117 -131.953 90)
		(property "Reference" "PC175"
			(at 0 0 90)
			(layer "F.SilkS")
			(hide yes)
			(effects
				(font
					(size 1.27 1.27)
				)
			)
		)
		(property "Value" "SC22U25V5MX-GP"
			(at -0.0762 -6.1214 90)
			(unlocked yes)
			(layer "F.Fab")
			(hide yes)
			(effects
				(font
					(size 1.016 1.016)
					(thickness 0.1524)
				)
			)
		)
		(property "Device Type" "C805H58"
			(at -0.0762 -8.1534 90)
			(unlocked yes)
			(layer "F.Fab")
			(hide yes)
			(effects
				(font
					(size 1.016 1.016)
					(thickness 0.1524)
				)
			)
		)
		(duplicate_pad_numbers_are_jumpers no)
		(fp_line
			(start 0.635 0)
			(end -0.635 0)
			(stroke
				(width 0.508)
				(type default)
			)
			(layer "F.SilkS")
		)
		(fp_rect
			(start -0.9652 1.778)
			(end 0.9652 -1.778)
			(stroke
				(width 0)
				(type default)
			)
			(fill no)
			(layer "F.CrtYd")
		)
		(fp_poly
			(pts
				(xy -0.9652 -1.778) (xy 0.9652 -1.778) (xy 0.9652 1.778) (xy -0.9652 1.778)
			)
			(stroke
				(width 0)
				(type default)
			)
			(fill no)
			(layer "F.Fab")
		)
		(pad "1" smd rect
			(at 0 -0.9652 90)
			(size 1.397 1.143)
			(layers "F.Cu" "F.Mask" "F.Paste")
			(net "P0V9_E_VIN")
		)
		(pad "2" smd rect
			(at 0 0.9652 90)
			(size 1.397 1.143)
			(layers "F.Cu" "F.Mask" "F.Paste")
			(net "GND")
		)
	)
	(footprint ""
		(layer "F.Cu")
		(at 14.682216 -221.67088 -90)
		(property "Reference" "SR296"
			(at 0 0 270)
			(layer "F.SilkS")
			(hide yes)
			(effects
				(font
					(size 1.27 1.27)
				)
			)
		)
		(property "Value" "0R2J-2-GP"
			(at 0.064008 -3.993896 270)
			(unlocked yes)
			(layer "F.Fab")
			(hide yes)
			(effects
				(font
					(size 1.016 1.016)
					(thickness 0.1524)
				)
			)
		)
		(property "Device Type" "R402H16"
			(at 0.064008 -5.517896 270)
			(unlocked yes)
			(layer "F.Fab")
			(hide yes)
			(effects
				(font
					(size 1.016 1.016)
					(thickness 0.1524)
				)
			)
		)
		(duplicate_pad_numbers_are_jumpers no)
		(fp_line
			(start -0.508 -0.9398)
			(end -0.508 0.9398)
			(stroke
				(width 0.1524)
				(type default)
			)
			(layer "F.SilkS")
		)
		(fp_line
			(start 0.508 -0.9398)
			(end -0.508 -0.9398)
			(stroke
				(width 0.1524)
				(type default)
			)
			(layer "F.SilkS")
		)
		(fp_rect
			(start -0.508 0.9398)
			(end 0.508 -0.9398)
			(stroke
				(width 0)
				(type default)
			)
			(fill no)
			(layer "F.CrtYd")
		)
		(fp_rect
			(start -0.508 0.9398)
			(end 0.508 -0.9398)
			(stroke
				(width 0)
				(type default)
			)
			(fill no)
			(layer "F.Fab")
		)
		(pad "1" smd custom
			(at 0 -0.4445 270)
			(size 0.1397 0.1397)
			(layers "F.Cu" "F.Mask" "F.Paste")
			(net "PWR_SCL")
			(options
				(clearance outline)
				(anchor circle)
			)
			(primitives
				(gr_poly
					(pts
						(arc
							(start -0.1778 -0.2794)
							(mid -0.249642 -0.249642)
							(end -0.2794 -0.1778)
						)
						(arc
							(start -0.2794 0.1778)
							(mid -0.249642 0.249642)
							(end -0.1778 0.2794)
						)
						(arc
							(start 0.1778 0.2794)
							(mid 0.249642 0.249642)
							(end 0.2794 0.1778)
						)
						(arc
							(start 0.2794 -0.1778)
							(mid 0.249642 -0.249642)
							(end 0.1778 -0.2794)
						)
					)
					(width 0)
					(fill yes)
				)
			)
		)
		(pad "2" smd custom
			(at 0 0.4445 270)
			(size 0.1397 0.1397)
			(layers "F.Cu" "F.Mask" "F.Paste")
			(net "BMC_IOEXP_SCL_10")
			(options
				(clearance outline)
				(anchor circle)
			)
			(primitives
				(gr_poly
					(pts
						(arc
							(start -0.1778 -0.2794)
							(mid -0.249642 -0.249642)
							(end -0.2794 -0.1778)
						)
						(arc
							(start -0.2794 0.1778)
							(mid -0.249642 0.249642)
							(end -0.1778 0.2794)
						)
						(arc
							(start 0.1778 0.2794)
							(mid 0.249642 0.249642)
							(end 0.2794 0.1778)
						)
						(arc
							(start 0.2794 -0.1778)
							(mid 0.249642 -0.249642)
							(end 0.1778 -0.2794)
						)
					)
					(width 0)
					(fill yes)
				)
			)
		)
	)
	(footprint ""
		(layer "F.Cu")
		(at 307.20538 -144.02054)
		(property "Reference" "C7788"
			(at 0 0 0)
			(layer "F.SilkS")
			(hide yes)
			(effects
				(font
					(size 1.27 1.27)
				)
			)
		)
		(property "Value" "SCD1U16V2KX-3GP"
			(at 1.1811 -2.7051 0)
			(unlocked yes)
			(layer "F.Fab")
			(hide yes)
			(effects
				(font
					(size 1.016 1.016)
					(thickness 0.1524)
				)
			)
		)
		(property "Device Type" "C402H22"
			(at 1.1811 -4.2291 0)
			(unlocked yes)
			(layer "F.Fab")
			(hide yes)
			(effects
				(font
					(size 1.016 1.016)
					(thickness 0.1524)
				)
			)
		)
		(duplicate_pad_numbers_are_jumpers no)
		(fp_rect
			(start -0.4318 0.9525)
			(end 0.4318 -0.9525)
			(stroke
				(width 0)
				(type default)
			)
			(fill no)
			(layer "F.CrtYd")
		)
		(fp_rect
			(start -0.4318 0.9525)
			(end 0.4318 -0.9525)
			(stroke
				(width 0)
				(type default)
			)
			(fill no)
			(layer "F.Fab")
		)
		(pad "1" smd custom
			(at 0 -0.4445)
			(size 0.1524 0.1524)
			(layers "F.Cu" "F.Mask" "F.Paste")
			(net "P3V3_STBY")
			(options
				(clearance outline)
				(anchor circle)
			)
			(primitives
				(gr_poly
					(pts
						(arc
							(start 0.3048 -0.2032)
							(mid 0.275042 -0.275042)
							(end 0.2032 -0.3048)
						)
						(arc
							(start -0.2032 -0.3048)
							(mid -0.275042 -0.275042)
							(end -0.3048 -0.2032)
						)
						(arc
							(start -0.3048 0.2032)
							(mid -0.275042 0.275042)
							(end -0.2032 0.3048)
						)
						(arc
							(start 0.2032 0.3048)
							(mid 0.275042 0.275042)
							(end 0.3048 0.2032)
						)
					)
					(width 0)
					(fill yes)
				)
			)
		)
		(pad "2" smd custom
			(at 0 0.4445)
			(size 0.1524 0.1524)
			(layers "F.Cu" "F.Mask" "F.Paste")
			(net "GND")
			(options
				(clearance outline)
				(anchor circle)
			)
			(primitives
				(gr_poly
					(pts
						(arc
							(start 0.3048 -0.2032)
							(mid 0.275042 -0.275042)
							(end 0.2032 -0.3048)
						)
						(arc
							(start -0.2032 -0.3048)
							(mid -0.275042 -0.275042)
							(end -0.3048 -0.2032)
						)
						(arc
							(start -0.3048 0.2032)
							(mid -0.275042 0.275042)
							(end -0.2032 0.3048)
						)
						(arc
							(start 0.2032 0.3048)
							(mid 0.275042 0.275042)
							(end 0.3048 0.2032)
						)
					)
					(width 0)
					(fill yes)
				)
			)
		)
	)
)
